(kicad_pcb
	(version 20260206)
	(generator "pcbnew")
	(generator_version "10.0")
	(general
		(thickness 1.6)
		(legacy_teardrops no)
	)
	(paper "A4")
	(title_block
		(title "baseboard — 13948-1b.1110WZS1818.brd")
		(comment 1 "Honey Badger (Wiwynn) / footprints 653-660 of 2523")
	)
	(layers
		(0 "F.Cu" signal "TOP")
		(4 "In1.Cu" signal "L2GND")
		(6 "In2.Cu" signal "L3")
		(8 "In3.Cu" signal "L4VCC")
		(10 "In4.Cu" signal "L5VCC")
		(12 "In5.Cu" signal "L6")
		(14 "In6.Cu" signal "L7GND")
		(2 "B.Cu" signal "BOTTOM")
		(9 "F.Adhes" user "F.Adhesive")
		(11 "B.Adhes" user "B.Adhesive")
		(13 "F.Paste" user "Package Geometry/Pastemask Top")
		(15 "B.Paste" user "Package Geometry/Pastemask Bottom")
		(5 "F.SilkS" user "Ref Des/Silkscreen Top")
		(7 "B.SilkS" user "Ref Des/Silkscreen Bottom")
		(1 "F.Mask" user "Board Geometry/Soldermask Top")
		(3 "B.Mask" user "Board Geometry/Soldermask Bottom")
		(17 "Dwgs.User" user "User.Drawings")
		(19 "Cmts.User" user "User.Comments")
		(21 "Eco1.User" user "User.Eco1")
		(23 "Eco2.User" user "User.Eco2")
		(25 "Edge.Cuts" user "Board Geometry/Outline")
		(27 "Margin" user)
		(31 "F.CrtYd" user "Package Geometry/Place Bound Top")
		(29 "B.CrtYd" user "Package Geometry/Place Bound Bottom")
		(35 "F.Fab" user "Ref Des/Assembly Top")
		(33 "B.Fab" user "Ref Des/Assembly Bottom")
	)
	(footprint ""
		(layer "F.Cu")
		(at 316.484 -68.199 -90)
		(property "Reference" "R273"
			(at 0 0 270)
			(layer "F.SilkS")
			(hide yes)
			(effects
				(font
					(size 1.27 1.27)
				)
			)
		)
		(property "Value" "0R2J-2-GP"
			(at 0.064008 -3.993896 270)
			(unlocked yes)
			(layer "F.Fab")
			(hide yes)
			(effects
				(font
					(size 1.016 1.016)
					(thickness 0.1524)
				)
			)
		)
		(property "Device Type" "R402H16"
			(at 0.064008 -5.517896 270)
			(unlocked yes)
			(layer "F.Fab")
			(hide yes)
			(effects
				(font
					(size 1.016 1.016)
					(thickness 0.1524)
				)
			)
		)
		(duplicate_pad_numbers_are_jumpers no)
		(fp_line
			(start -0.508 -0.9398)
			(end -0.508 0.9398)
			(stroke
				(width 0.1524)
				(type default)
			)
			(layer "F.SilkS")
		)
		(fp_line
			(start 0.508 -0.9398)
			(end -0.508 -0.9398)
			(stroke
				(width 0.1524)
				(type default)
			)
			(layer "F.SilkS")
		)
		(fp_rect
			(start -0.508 0.9398)
			(end 0.508 -0.9398)
			(stroke
				(width 0)
				(type default)
			)
			(fill no)
			(layer "F.CrtYd")
		)
		(fp_rect
			(start -0.508 0.9398)
			(end 0.508 -0.9398)
			(stroke
				(width 0)
				(type default)
			)
			(fill no)
			(layer "F.Fab")
		)
		(pad "1" smd custom
			(at 0 -0.4445 270)
			(size 0.1397 0.1397)
			(layers "F.Cu" "F.Mask" "F.Paste")
			(net "CLK_100M_CLKBUFF_ENET2_DP")
			(options
				(clearance outline)
				(anchor circle)
			)
			(primitives
				(gr_poly
					(pts
						(arc
							(start -0.1778 -0.2794)
							(mid -0.249642 -0.249642)
							(end -0.2794 -0.1778)
						)
						(arc
							(start -0.2794 0.1778)
							(mid -0.249642 0.249642)
							(end -0.1778 0.2794)
						)
						(arc
							(start 0.1778 0.2794)
							(mid 0.249642 0.249642)
							(end 0.2794 0.1778)
						)
						(arc
							(start 0.2794 -0.1778)
							(mid 0.249642 -0.249642)
							(end 0.1778 -0.2794)
						)
					)
					(width 0)
					(fill yes)
				)
			)
		)
		(pad "2" smd custom
			(at 0 0.4445 270)
			(size 0.1397 0.1397)
			(layers "F.Cu" "F.Mask" "F.Paste")
			(net "PCIE_10G_REFCLK_2_P")
			(options
				(clearance outline)
				(anchor circle)
			)
			(primitives
				(gr_poly
					(pts
						(arc
							(start -0.1778 -0.2794)
							(mid -0.249642 -0.249642)
							(end -0.2794 -0.1778)
						)
						(arc
							(start -0.2794 0.1778)
							(mid -0.249642 0.249642)
							(end -0.1778 0.2794)
						)
						(arc
							(start 0.1778 0.2794)
							(mid 0.249642 0.249642)
							(end 0.2794 0.1778)
						)
						(arc
							(start 0.2794 -0.1778)
							(mid 0.249642 -0.249642)
							(end 0.1778 -0.2794)
						)
					)
					(width 0)
					(fill yes)
				)
			)
		)
	)
	(footprint ""
		(layer "F.Cu")
		(at 326.263 -82.55 180)
		(property "Reference" "R684"
			(at 0 0 180)
			(layer "F.SilkS")
			(hide yes)
			(effects
				(font
					(size 1.27 1.27)
				)
			)
		)
		(property "Value" "0R2J-2-GP"
			(at 0.064008 -3.993896 180)
			(unlocked yes)
			(layer "F.Fab")
			(hide yes)
			(effects
				(font
					(size 1.016 1.016)
					(thickness 0.1524)
				)
			)
		)
		(property "Device Type" "R402H16"
			(at 0.064008 -5.517896 180)
			(unlocked yes)
			(layer "F.Fab")
			(hide yes)
			(effects
				(font
					(size 1.016 1.016)
					(thickness 0.1524)
				)
			)
		)
		(duplicate_pad_numbers_are_jumpers no)
		(fp_line
			(start 0.508 -0.9398)
			(end -0.508 -0.9398)
			(stroke
				(width 0.1524)
				(type default)
			)
			(layer "F.SilkS")
		)
		(fp_line
			(start -0.508 -0.9398)
			(end -0.508 0.9398)
			(stroke
				(width 0.1524)
				(type default)
			)
			(layer "F.SilkS")
		)
		(fp_rect
			(start -0.508 0.9398)
			(end 0.508 -0.9398)
			(stroke
				(width 0)
				(type default)
			)
			(fill no)
			(layer "F.CrtYd")
		)
		(fp_rect
			(start -0.508 0.9398)
			(end 0.508 -0.9398)
			(stroke
				(width 0)
				(type default)
			)
			(fill no)
			(layer "F.Fab")
		)
		(pad "1" smd custom
			(at 0 -0.4445 180)
			(size 0.1397 0.1397)
			(layers "F.Cu" "F.Mask" "F.Paste")
			(net "FLA_CS_1")
			(options
				(clearance outline)
				(anchor circle)
			)
			(primitives
				(gr_poly
					(pts
						(arc
							(start -0.1778 -0.2794)
							(mid -0.249642 -0.249642)
							(end -0.2794 -0.1778)
						)
						(arc
							(start -0.2794 0.1778)
							(mid -0.249642 0.249642)
							(end -0.1778 0.2794)
						)
						(arc
							(start 0.1778 0.2794)
							(mid 0.249642 0.249642)
							(end 0.2794 0.1778)
						)
						(arc
							(start 0.2794 -0.1778)
							(mid 0.249642 -0.249642)
							(end 0.1778 -0.2794)
						)
					)
					(width 0)
					(fill yes)
				)
			)
		)
		(pad "2" smd custom
			(at 0 0.4445 180)
			(size 0.1397 0.1397)
			(layers "F.Cu" "F.Mask" "F.Paste")
			(net "FLA_CS_1_R")
			(options
				(clearance outline)
				(anchor circle)
			)
			(primitives
				(gr_poly
					(pts
						(arc
							(start -0.1778 -0.2794)
							(mid -0.249642 -0.249642)
							(end -0.2794 -0.1778)
						)
						(arc
							(start -0.2794 0.1778)
							(mid -0.249642 0.249642)
							(end -0.1778 0.2794)
						)
						(arc
							(start 0.1778 0.2794)
							(mid 0.249642 0.249642)
							(end 0.2794 0.1778)
						)
						(arc
							(start 0.2794 -0.1778)
							(mid 0.249642 -0.249642)
							(end 0.1778 -0.2794)
						)
					)
					(width 0)
					(fill yes)
				)
			)
		)
	)
	(footprint ""
		(layer "F.Cu")
		(at 144.653 -111.633 -90)
		(property "Reference" "SC1189"
			(at 0 0 270)
			(layer "F.SilkS")
			(hide yes)
			(effects
				(font
					(size 1.27 1.27)
				)
			)
		)
		(property "Value" "SC22U6D3V5MX-2GP"
			(at -0.0762 -6.1214 270)
			(unlocked yes)
			(layer "F.Fab")
			(hide yes)
			(effects
				(font
					(size 1.016 1.016)
					(thickness 0.1524)
				)
			)
		)
		(property "Device Type" "C805H58"
			(at -0.0762 -8.1534 270)
			(unlocked yes)
			(layer "F.Fab")
			(hide yes)
			(effects
				(font
					(size 1.016 1.016)
					(thickness 0.1524)
				)
			)
		)
		(duplicate_pad_numbers_are_jumpers no)
		(fp_line
			(start 0.635 0)
			(end -0.635 0)
			(stroke
				(width 0.508)
				(type default)
			)
			(layer "F.SilkS")
		)
		(fp_rect
			(start -0.9652 1.778)
			(end 0.9652 -1.778)
			(stroke
				(width 0)
				(type default)
			)
			(fill no)
			(layer "F.CrtYd")
		)
		(fp_poly
			(pts
				(xy -0.9652 -1.778) (xy 0.9652 -1.778) (xy 0.9652 1.778) (xy -0.9652 1.778)
			)
			(stroke
				(width 0)
				(type default)
			)
			(fill no)
			(layer "F.Fab")
		)
		(pad "1" smd rect
			(at 0 -0.9652 270)
			(size 1.397 1.143)
			(layers "F.Cu" "F.Mask" "F.Paste")
			(net "GB_VDDA")
		)
		(pad "2" smd rect
			(at 0 0.9652 270)
			(size 1.397 1.143)
			(layers "F.Cu" "F.Mask" "F.Paste")
			(net "GND")
		)
	)
	(footprint ""
		(layer "F.Cu")
		(at 34.798 -169.291 90)
		(property "Reference" "SR1279"
			(at 0 0 90)
			(layer "F.SilkS")
			(hide yes)
			(effects
				(font
					(size 1.27 1.27)
				)
			)
		)
		(property "Value" "4K7R2F-GP"
			(at 0.064008 -3.993896 90)
			(unlocked yes)
			(layer "F.Fab")
			(hide yes)
			(effects
				(font
					(size 1.016 1.016)
					(thickness 0.1524)
				)
			)
		)
		(property "Device Type" "R402H16"
			(at 0.064008 -5.517896 90)
			(unlocked yes)
			(layer "F.Fab")
			(hide yes)
			(effects
				(font
					(size 1.016 1.016)
					(thickness 0.1524)
				)
			)
		)
		(duplicate_pad_numbers_are_jumpers no)
		(fp_line
			(start 0.508 -0.9398)
			(end -0.508 -0.9398)
			(stroke
				(width 0.1524)
				(type default)
			)
			(layer "F.SilkS")
		)
		(fp_line
			(start -0.508 -0.9398)
			(end -0.508 0.9398)
			(stroke
				(width 0.1524)
				(type default)
			)
			(layer "F.SilkS")
		)
		(fp_rect
			(start -0.508 0.9398)
			(end 0.508 -0.9398)
			(stroke
				(width 0)
				(type default)
			)
			(fill no)
			(layer "F.CrtYd")
		)
		(fp_rect
			(start -0.508 0.9398)
			(end 0.508 -0.9398)
			(stroke
				(width 0)
				(type default)
			)
			(fill no)
			(layer "F.Fab")
		)
		(pad "1" smd custom
			(at 0 -0.4445 90)
			(size 0.1397 0.1397)
			(layers "F.Cu" "F.Mask" "F.Paste")
			(net "P3V3_STBY")
			(options
				(clearance outline)
				(anchor circle)
			)
			(primitives
				(gr_poly
					(pts
						(arc
							(start -0.1778 -0.2794)
							(mid -0.249642 -0.249642)
							(end -0.2794 -0.1778)
						)
						(arc
							(start -0.2794 0.1778)
							(mid -0.249642 0.249642)
							(end -0.1778 0.2794)
						)
						(arc
							(start 0.1778 0.2794)
							(mid 0.249642 0.249642)
							(end 0.2794 0.1778)
						)
						(arc
							(start 0.2794 -0.1778)
							(mid 0.249642 -0.249642)
							(end 0.1778 -0.2794)
						)
					)
					(width 0)
					(fill yes)
				)
			)
		)
		(pad "2" smd custom
			(at 0 0.4445 90)
			(size 0.1397 0.1397)
			(layers "F.Cu" "F.Mask" "F.Paste")
			(net "DP_BMC_EXP_RST_N")
			(options
				(clearance outline)
				(anchor circle)
			)
			(primitives
				(gr_poly
					(pts
						(arc
							(start -0.1778 -0.2794)
							(mid -0.249642 -0.249642)
							(end -0.2794 -0.1778)
						)
						(arc
							(start -0.2794 0.1778)
							(mid -0.249642 0.249642)
							(end -0.1778 0.2794)
						)
						(arc
							(start 0.1778 0.2794)
							(mid 0.249642 0.249642)
							(end 0.2794 0.1778)
						)
						(arc
							(start 0.2794 -0.1778)
							(mid 0.249642 -0.249642)
							(end 0.1778 -0.2794)
						)
					)
					(width 0)
					(fill yes)
				)
			)
		)
	)
	(footprint ""
		(layer "F.Cu")
		(at 319.913 -169.545 -90)
		(property "Reference" "R441"
			(at 0 0 270)
			(layer "F.SilkS")
			(hide yes)
			(effects
				(font
					(size 1.27 1.27)
				)
			)
		)
		(property "Value" "10KR2F-2-GP"
			(at 0.064008 -3.993896 270)
			(unlocked yes)
			(layer "F.Fab")
			(hide yes)
			(effects
				(font
					(size 1.016 1.016)
					(thickness 0.1524)
				)
			)
		)
		(property "Device Type" "R402H16"
			(at 0.064008 -5.517896 270)
			(unlocked yes)
			(layer "F.Fab")
			(hide yes)
			(effects
				(font
					(size 1.016 1.016)
					(thickness 0.1524)
				)
			)
		)
		(duplicate_pad_numbers_are_jumpers no)
		(fp_line
			(start -0.508 -0.9398)
			(end -0.508 0.9398)
			(stroke
				(width 0.1524)
				(type default)
			)
			(layer "F.SilkS")
		)
		(fp_line
			(start 0.508 -0.9398)
			(end -0.508 -0.9398)
			(stroke
				(width 0.1524)
				(type default)
			)
			(layer "F.SilkS")
		)
		(fp_rect
			(start -0.508 0.9398)
			(end 0.508 -0.9398)
			(stroke
				(width 0)
				(type default)
			)
			(fill no)
			(layer "F.CrtYd")
		)
		(fp_rect
			(start -0.508 0.9398)
			(end 0.508 -0.9398)
			(stroke
				(width 0)
				(type default)
			)
			(fill no)
			(layer "F.Fab")
		)
		(pad "1" smd custom
			(at 0 -0.4445 270)
			(size 0.1397 0.1397)
			(layers "F.Cu" "F.Mask" "F.Paste")
			(net "P3V3_STBY")
			(options
				(clearance outline)
				(anchor circle)
			)
			(primitives
				(gr_poly
					(pts
						(arc
							(start -0.1778 -0.2794)
							(mid -0.249642 -0.249642)
							(end -0.2794 -0.1778)
						)
						(arc
							(start -0.2794 0.1778)
							(mid -0.249642 0.249642)
							(end -0.1778 0.2794)
						)
						(arc
							(start 0.1778 0.2794)
							(mid 0.249642 0.249642)
							(end 0.2794 0.1778)
						)
						(arc
							(start 0.2794 -0.1778)
							(mid 0.249642 -0.249642)
							(end 0.1778 -0.2794)
						)
					)
					(width 0)
					(fill yes)
				)
			)
		)
		(pad "2" smd custom
			(at 0 0.4445 270)
			(size 0.1397 0.1397)
			(layers "F.Cu" "F.Mask" "F.Paste")
			(net "BMC_I2C_B_SCL")
			(options
				(clearance outline)
				(anchor circle)
			)
			(primitives
				(gr_poly
					(pts
						(arc
							(start -0.1778 -0.2794)
							(mid -0.249642 -0.249642)
							(end -0.2794 -0.1778)
						)
						(arc
							(start -0.2794 0.1778)
							(mid -0.249642 0.249642)
							(end -0.1778 0.2794)
						)
						(arc
							(start 0.1778 0.2794)
							(mid 0.249642 0.249642)
							(end 0.2794 0.1778)
						)
						(arc
							(start 0.2794 -0.1778)
							(mid 0.249642 -0.249642)
							(end 0.1778 -0.2794)
						)
					)
					(width 0)
					(fill yes)
				)
			)
		)
	)
	(footprint ""
		(layer "F.Cu")
		(at 152.019 -54.356 90)
		(property "Reference" "SR699"
			(at 0 0 90)
			(layer "F.SilkS")
			(hide yes)
			(effects
				(font
					(size 1.27 1.27)
				)
			)
		)
		(property "Value" "10KR2F-2-GP"
			(at 0.064008 -3.993896 90)
			(unlocked yes)
			(layer "F.Fab")
			(hide yes)
			(effects
				(font
					(size 1.016 1.016)
					(thickness 0.1524)
				)
			)
		)
		(property "Device Type" "R402H16"
			(at 0.064008 -5.517896 90)
			(unlocked yes)
			(layer "F.Fab")
			(hide yes)
			(effects
				(font
					(size 1.016 1.016)
					(thickness 0.1524)
				)
			)
		)
		(duplicate_pad_numbers_are_jumpers no)
		(fp_line
			(start 0.508 -0.9398)
			(end -0.508 -0.9398)
			(stroke
				(width 0.1524)
				(type default)
			)
			(layer "F.SilkS")
		)
		(fp_line
			(start -0.508 -0.9398)
			(end -0.508 0.9398)
			(stroke
				(width 0.1524)
				(type default)
			)
			(layer "F.SilkS")
		)
		(fp_rect
			(start -0.508 0.9398)
			(end 0.508 -0.9398)
			(stroke
				(width 0)
				(type default)
			)
			(fill no)
			(layer "F.CrtYd")
		)
		(fp_rect
			(start -0.508 0.9398)
			(end 0.508 -0.9398)
			(stroke
				(width 0)
				(type default)
			)
			(fill no)
			(layer "F.Fab")
		)
		(pad "1" smd custom
			(at 0 -0.4445 90)
			(size 0.1397 0.1397)
			(layers "F.Cu" "F.Mask" "F.Paste")
			(net "XM_ADDR_5")
			(options
				(clearance outline)
				(anchor circle)
			)
			(primitives
				(gr_poly
					(pts
						(arc
							(start -0.1778 -0.2794)
							(mid -0.249642 -0.249642)
							(end -0.2794 -0.1778)
						)
						(arc
							(start -0.2794 0.1778)
							(mid -0.249642 0.249642)
							(end -0.1778 0.2794)
						)
						(arc
							(start 0.1778 0.2794)
							(mid 0.249642 0.249642)
							(end 0.2794 0.1778)
						)
						(arc
							(start 0.2794 -0.1778)
							(mid 0.249642 -0.249642)
							(end 0.1778 -0.2794)
						)
					)
					(width 0)
					(fill yes)
				)
			)
		)
		(pad "2" smd custom
			(at 0 0.4445 90)
			(size 0.1397 0.1397)
			(layers "F.Cu" "F.Mask" "F.Paste")
			(net "GND")
			(options
				(clearance outline)
				(anchor circle)
			)
			(primitives
				(gr_poly
					(pts
						(arc
							(start -0.1778 -0.2794)
							(mid -0.249642 -0.249642)
							(end -0.2794 -0.1778)
						)
						(arc
							(start -0.2794 0.1778)
							(mid -0.249642 0.249642)
							(end -0.1778 0.2794)
						)
						(arc
							(start 0.1778 0.2794)
							(mid 0.249642 0.249642)
							(end 0.2794 0.1778)
						)
						(arc
							(start 0.2794 -0.1778)
							(mid 0.249642 -0.249642)
							(end 0.1778 -0.2794)
						)
					)
					(width 0)
					(fill yes)
				)
			)
		)
	)
	(footprint ""
		(layer "F.Cu")
		(at 268.4018 -44.704)
		(property "Reference" "PC49"
			(at 0 0 0)
			(layer "F.SilkS")
			(hide yes)
			(effects
				(font
					(size 1.27 1.27)
				)
			)
		)
		(property "Value" "SC1U10V3KX-4GP-U"
			(at 0 -2.8194 0)
			(unlocked yes)
			(layer "F.Fab")
			(hide yes)
			(effects
				(font
					(size 1.016 1.016)
					(thickness 0.1524)
				)
			)
		)
		(property "Device Type" "C603H36"
			(at 0 -4.3434 0)
			(unlocked yes)
			(layer "F.Fab")
			(hide yes)
			(effects
				(font
					(size 1.016 1.016)
					(thickness 0.1524)
				)
			)
		)
		(duplicate_pad_numbers_are_jumpers no)
		(fp_line
			(start 0.508 0)
			(end -0.508 0)
			(stroke
				(width 0.2032)
				(type default)
			)
			(layer "F.SilkS")
		)
		(fp_rect
			(start -0.5842 1.3335)
			(end 0.5842 -1.3335)
			(stroke
				(width 0)
				(type default)
			)
			(fill no)
			(layer "F.CrtYd")
		)
		(fp_rect
			(start -0.5842 1.3335)
			(end 0.5842 -1.3335)
			(stroke
				(width 0)
				(type default)
			)
			(fill no)
			(layer "F.Fab")
		)
		(pad "1" smd custom
			(at 0 -0.762)
			(size 0.2159 0.2159)
			(layers "F.Cu" "F.Mask" "F.Paste")
			(net "GND")
			(options
				(clearance outline)
				(anchor circle)
			)
			(primitives
				(gr_poly
					(pts
						(arc
							(start -0.3302 -0.4318)
							(mid -0.402042 -0.402042)
							(end -0.4318 -0.3302)
						)
						(arc
							(start -0.4318 0.3302)
							(mid -0.402042 0.402042)
							(end -0.3302 0.4318)
						)
						(arc
							(start 0.3302 0.4318)
							(mid 0.402042 0.402042)
							(end 0.4318 0.3302)
						)
						(arc
							(start 0.4318 -0.3302)
							(mid 0.402042 -0.402042)
							(end 0.3302 -0.4318)
						)
					)
					(width 0)
					(fill yes)
				)
			)
		)
		(pad "2" smd custom
			(at 0 0.762)
			(size 0.2159 0.2159)
			(layers "F.Cu" "F.Mask" "F.Paste")
			(net "P1V8_STBY_VREG")
			(options
				(clearance outline)
				(anchor circle)
			)
			(primitives
				(gr_poly
					(pts
						(arc
							(start -0.3302 -0.4318)
							(mid -0.402042 -0.402042)
							(end -0.4318 -0.3302)
						)
						(arc
							(start -0.4318 0.3302)
							(mid -0.402042 0.402042)
							(end -0.3302 0.4318)
						)
						(arc
							(start 0.3302 0.4318)
							(mid 0.402042 0.402042)
							(end 0.4318 0.3302)
						)
						(arc
							(start 0.4318 -0.3302)
							(mid 0.402042 -0.402042)
							(end 0.3302 -0.4318)
						)
					)
					(width 0)
					(fill yes)
				)
			)
		)
	)
	(footprint ""
		(layer "F.Cu")
		(at 303.53 -102.108)
		(property "Reference" "R164"
			(at 0 0 0)
			(layer "F.SilkS")
			(hide yes)
			(effects
				(font
					(size 1.27 1.27)
				)
			)
		)
		(property "Value" "4K7R2F-GP"
			(at 0.064008 -3.993896 0)
			(unlocked yes)
			(layer "F.Fab")
			(hide yes)
			(effects
				(font
					(size 1.016 1.016)
					(thickness 0.1524)
				)
			)
		)
		(property "Device Type" "R402H16"
			(at 0.064008 -5.517896 0)
			(unlocked yes)
			(layer "F.Fab")
			(hide yes)
			(effects
				(font
					(size 1.016 1.016)
					(thickness 0.1524)
				)
			)
		)
		(duplicate_pad_numbers_are_jumpers no)
		(fp_line
			(start -0.508 -0.9398)
			(end -0.508 0.9398)
			(stroke
				(width 0.1524)
				(type default)
			)
			(layer "F.SilkS")
		)
		(fp_line
			(start 0.508 -0.9398)
			(end -0.508 -0.9398)
			(stroke
				(width 0.1524)
				(type default)
			)
			(layer "F.SilkS")
		)
		(fp_rect
			(start -0.508 0.9398)
			(end 0.508 -0.9398)
			(stroke
				(width 0)
				(type default)
			)
			(fill no)
			(layer "F.CrtYd")
		)
		(fp_rect
			(start -0.508 0.9398)
			(end 0.508 -0.9398)
			(stroke
				(width 0)
				(type default)
			)
			(fill no)
			(layer "F.Fab")
		)
		(pad "1" smd custom
			(at 0 -0.4445)
			(size 0.1397 0.1397)
			(layers "F.Cu" "F.Mask" "F.Paste")
			(net "P3V3_STBY")
			(options
				(clearance outline)
				(anchor circle)
			)
			(primitives
				(gr_poly
					(pts
						(arc
							(start -0.1778 -0.2794)
							(mid -0.249642 -0.249642)
							(end -0.2794 -0.1778)
						)
						(arc
							(start -0.2794 0.1778)
							(mid -0.249642 0.249642)
							(end -0.1778 0.2794)
						)
						(arc
							(start 0.1778 0.2794)
							(mid 0.249642 0.249642)
							(end 0.2794 0.1778)
						)
						(arc
							(start 0.2794 -0.1778)
							(mid 0.249642 -0.249642)
							(end 0.1778 -0.2794)
						)
					)
					(width 0)
					(fill yes)
				)
			)
		)
		(pad "2" smd custom
			(at 0 0.4445)
			(size 0.1397 0.1397)
			(layers "F.Cu" "F.Mask" "F.Paste")
			(net "TEMP_2_A2")
			(options
				(clearance outline)
				(anchor circle)
			)
			(primitives
				(gr_poly
					(pts
						(arc
							(start -0.1778 -0.2794)
							(mid -0.249642 -0.249642)
							(end -0.2794 -0.1778)
						)
						(arc
							(start -0.2794 0.1778)
							(mid -0.249642 0.249642)
							(end -0.1778 0.2794)
						)
						(arc
							(start 0.1778 0.2794)
							(mid 0.249642 0.249642)
							(end 0.2794 0.1778)
						)
						(arc
							(start 0.2794 -0.1778)
							(mid 0.249642 -0.249642)
							(end 0.1778 -0.2794)
						)
					)
					(width 0)
					(fill yes)
				)
			)
		)
	)
)
